# BASEBOARD_FAB2 (Tioga Pass) — schematic netlist excerpt (pin names and nets, part order shuffled) for the footprints in the layout excerpt that follows; sources: Cadence DE-HDL packaged netlist, KiCad conversion of Wiwynn_Tioga_Pass_MB.brd

C3N4  CAP_A  1.0UF 6.3V 10% X6S  pkg 0402V  page 132 : A = PVNN_PCH_STBY ; B = GND
R3L15  RES  68.1K 1% EMPTY  pkg 0402  page 236 : A = VR_PVNN_PCH_STBY_OCSET ; B = GND
C5U1  CAP  100UF 4V 20% X5R  pkg 0805  page 217 : A = PVDDQ_ABC ; B = GND

(kicad_pcb
	(version 20260206)
	(generator "pcbnew")
	(generator_version "10.0")
	(general
		(thickness 1.6)
		(legacy_teardrops no)
	)
	(paper "A4")
	(title_block
		(title "Wiwynn_Tioga_Pass_MB.brd")
		(comment 1 "Tioga Pass / footprints 2546-2548 of 4770")
	)
	(layers
		(0 "F.Cu" signal "TOP")
		(4 "In1.Cu" signal "L2GND")
		(6 "In2.Cu" signal "L3")
		(8 "In3.Cu" signal "L4GND")
		(10 "In4.Cu" signal "L5")
		(12 "In5.Cu" signal "L6GND")
		(14 "In6.Cu" signal "L7VCC")
		(16 "In7.Cu" signal "L8VCC")
		(18 "In8.Cu" signal "L9GND")
		(20 "In9.Cu" signal "L10")
		(22 "In10.Cu" signal "L11GND")
		(24 "In11.Cu" signal "L12")
		(26 "In12.Cu" signal "L13GND")
		(2 "B.Cu" signal "BOTTOM")
		(9 "F.Adhes" user "F.Adhesive")
		(11 "B.Adhes" user "B.Adhesive")
		(13 "F.Paste" user "Package Geometry/Pastemask Top")
		(15 "B.Paste" user "Package Geometry/Pastemask Bottom")
		(5 "F.SilkS" user "Ref Des/Silkscreen Top")
		(7 "B.SilkS" user "Ref Des/Silkscreen Bottom")
		(1 "F.Mask" user "Board Geometry/Soldermask Top")
		(3 "B.Mask" user "Board Geometry/Soldermask Bottom")
		(17 "Dwgs.User" user "User.Drawings")
		(19 "Cmts.User" user "User.Comments")
		(21 "Eco1.User" user "User.Eco1")
		(23 "Eco2.User" user "User.Eco2")
		(25 "Edge.Cuts" user "Board Geometry/Outline")
		(27 "Margin" user)
		(31 "F.CrtYd" user "Package Geometry/Place Bound Top")
		(29 "B.CrtYd" user "Package Geometry/Place Bound Bottom")
		(35 "F.Fab" user "Ref Des/Assembly Top")
		(33 "B.Fab" user "Ref Des/Assembly Bottom")
	)
	(footprint ""
		(layer "B.Cu")
		(at 375.3612 -156.337 -90)
		(property "Reference" "R3L15"
			(at 0 0 90)
			(layer "B.SilkS")
			(hide yes)
			(effects
				(font
					(size 1.27 1.27)
				)
				(justify mirror)
			)
		)
		(property "Value" ""
			(at 0 0 90)
			(layer "B.Fab")
			(effects
				(font
					(size 1.27 1.27)
				)
				(justify mirror)
			)
		)
		(duplicate_pad_numbers_are_jumpers no)
		(fp_poly
			(pts
				(xy 0.2794 -0.1016) (xy -0.2794 -0.1016) (xy -0.2794 0.9906) (xy 0.2794 0.9906)
			)
			(stroke
				(width 0)
				(type default)
			)
			(fill no)
			(layer "B.CrtYd")
		)
		(fp_line
			(start -0.2794 0.9906)
			(end -0.2794 -0.1016)
			(stroke
				(width 0.1)
				(type default)
			)
			(layer "B.Fab")
		)
		(fp_line
			(start 0.2794 0.9906)
			(end -0.2794 0.9906)
			(stroke
				(width 0.1)
				(type default)
			)
			(layer "B.Fab")
		)
		(fp_line
			(start -0.2794 -0.1016)
			(end 0.2794 -0.1016)
			(stroke
				(width 0.1)
				(type default)
			)
			(layer "B.Fab")
		)
		(fp_line
			(start 0.2794 -0.1016)
			(end 0.2794 0.9906)
			(stroke
				(width 0.1)
				(type default)
			)
			(layer "B.Fab")
		)
		(pad "1" smd rect
			(at 0 0 90)
			(size 0.508 0.508)
			(layers "B.Cu" "B.Mask" "B.Paste")
			(net "VR_PVNN_PCH_STBY_OCSET")
		)
		(pad "2" smd rect
			(at 0 0.889 90)
			(size 0.508 0.508)
			(layers "B.Cu" "B.Mask" "B.Paste")
			(net "GND")
		)
		(zone
			(layer "B.Cu")
			(hatch none 0.5)
			(connect_pads
				(clearance 0)
			)
			(min_thickness 0.25)
			(keepout
				(tracks not_allowed)
				(vias allowed)
				(pads allowed)
				(copperpour not_allowed)
				(footprints allowed)
			)
			(placement
				(enabled no)
				(sheetname "")
			)
			(fill
				(thermal_gap 0.5)
				(thermal_bridge_width 0.5)
				(island_removal_mode 0)
			)
			(polygon
				(pts
					(xy 374.7262 -156.083) (xy 374.7262 -156.591) (xy 375.1072 -156.591) (xy 375.1072 -156.083)
				)
			)
		)
		(zone
			(layer "B.Cu")
			(hatch none 0.5)
			(connect_pads
				(clearance 0)
			)
			(min_thickness 0.25)
			(keepout
				(tracks allowed)
				(vias not_allowed)
				(pads allowed)
				(copperpour not_allowed)
				(footprints allowed)
			)
			(placement
				(enabled no)
				(sheetname "")
			)
			(fill
				(thermal_gap 0.5)
				(thermal_bridge_width 0.5)
				(island_removal_mode 0)
			)
			(polygon
				(pts
					(xy 375.1072 -156.083) (xy 375.1072 -156.591) (xy 374.7262 -156.591) (xy 374.7262 -156.083)
				)
			)
		)
	)
	(footprint ""
		(layer "B.Cu")
		(at 259.6642 -17.5514 90)
		(property "Reference" "C5U1"
			(at 0 0 90)
			(layer "B.SilkS")
			(hide yes)
			(effects
				(font
					(size 1.27 1.27)
				)
				(justify mirror)
			)
		)
		(property "Value" ""
			(at 0 0 90)
			(layer "B.Fab")
			(effects
				(font
					(size 1.27 1.27)
				)
				(justify mirror)
			)
		)
		(duplicate_pad_numbers_are_jumpers no)
		(fp_rect
			(start -0.7239 -0.2159)
			(end 0.7239 1.9939)
			(stroke
				(width 0)
				(type default)
			)
			(fill no)
			(layer "B.CrtYd")
		)
		(fp_line
			(start 0.7239 -0.2159)
			(end 0.7239 1.9939)
			(stroke
				(width 0.1)
				(type default)
			)
			(layer "B.Fab")
		)
		(fp_line
			(start -0.7239 -0.2159)
			(end 0.7239 -0.2159)
			(stroke
				(width 0.1)
				(type default)
			)
			(layer "B.Fab")
		)
		(fp_line
			(start 0.7239 1.9939)
			(end -0.7239 1.9939)
			(stroke
				(width 0.1)
				(type default)
			)
			(layer "B.Fab")
		)
		(fp_line
			(start -0.7239 1.9939)
			(end -0.7239 -0.2159)
			(stroke
				(width 0.1)
				(type default)
			)
			(layer "B.Fab")
		)
		(pad "1" smd rect
			(at 0 0 270)
			(size 1.27 1.016)
			(layers "B.Cu" "B.Mask" "B.Paste")
			(net "PVDDQ_ABC")
		)
		(pad "2" smd rect
			(at 0 1.778 270)
			(size 1.27 1.016)
			(layers "B.Cu" "B.Mask" "B.Paste")
			(net "GND")
		)
		(zone
			(layer "B.Cu")
			(hatch none 0.5)
			(connect_pads
				(clearance 0)
			)
			(min_thickness 0.25)
			(keepout
				(tracks not_allowed)
				(vias allowed)
				(pads allowed)
				(copperpour not_allowed)
				(footprints allowed)
			)
			(placement
				(enabled no)
				(sheetname "")
			)
			(fill
				(thermal_gap 0.5)
				(thermal_bridge_width 0.5)
				(island_removal_mode 0)
			)
			(polygon
				(pts
					(xy 260.1722 -16.9164) (xy 260.9342 -16.9164) (xy 260.9342 -18.1864) (xy 260.1722 -18.1864)
				)
			)
		)
	)
	(footprint ""
		(layer "B.Cu")
		(at 387.73735 -111.05515 180)
		(property "Reference" "C3N4"
			(at 0 0 0)
			(layer "B.SilkS")
			(hide yes)
			(effects
				(font
					(size 1.27 1.27)
				)
				(justify mirror)
			)
		)
		(property "Value" ""
			(at 0 0 0)
			(layer "B.Fab")
			(effects
				(font
					(size 1.27 1.27)
				)
				(justify mirror)
			)
		)
		(duplicate_pad_numbers_are_jumpers no)
		(fp_rect
			(start 0.2794 0.9144)
			(end -0.2794 -0.1143)
			(stroke
				(width 0)
				(type default)
			)
			(fill no)
			(layer "B.CrtYd")
		)
		(fp_line
			(start 0.2794 0.9144)
			(end 0.2794 -0.1143)
			(stroke
				(width 0.1)
				(type default)
			)
			(layer "B.Fab")
		)
		(fp_line
			(start 0.2794 -0.1143)
			(end -0.2794 -0.1143)
			(stroke
				(width 0.1)
				(type default)
			)
			(layer "B.Fab")
		)
		(fp_line
			(start -0.2794 0.9144)
			(end 0.2794 0.9144)
			(stroke
				(width 0.1)
				(type default)
			)
			(layer "B.Fab")
		)
		(fp_line
			(start -0.2794 -0.1143)
			(end -0.2794 0.9144)
			(stroke
				(width 0.1)
				(type default)
			)
			(layer "B.Fab")
		)
		(pad "1" smd custom
			(at 0 0 90)
			(size 0.10414 0.10414)
			(layers "B.Cu" "B.Mask" "B.Paste")
			(net "PVNN_PCH_STBY")
			(options
				(clearance outline)
				(anchor circle)
			)
			(primitives
				(gr_poly
					(pts
						(xy -0.20828 -0.08636) (xy -0.20828 0.08636) (xy -0.08636 0.20828) (xy 0.086614 0.20828) (xy 0.20828 0.086614)
						(xy 0.20828 -0.08636) (xy 0.08636 -0.20828) (xy -0.08636 -0.20828)
					)
					(width 0)
					(fill yes)
				)
			)
		)
		(pad "2" smd custom
			(at 0 0.8001 90)
			(size 0.10414 0.10414)
			(layers "B.Cu" "B.Mask" "B.Paste")
			(net "GND")
			(options
				(clearance outline)
				(anchor circle)
			)
			(primitives
				(gr_poly
					(pts
						(xy -0.20828 -0.08636) (xy -0.20828 0.08636) (xy -0.08636 0.20828) (xy 0.086614 0.20828) (xy 0.20828 0.086614)
						(xy 0.20828 -0.08636) (xy 0.08636 -0.20828) (xy -0.08636 -0.20828)
					)
					(width 0)
					(fill yes)
				)
			)
		)
		(zone
			(layer "B.Cu")
			(hatch none 0.5)
			(connect_pads
				(clearance 0)
			)
			(min_thickness 0.25)
			(keepout
				(tracks allowed)
				(vias not_allowed)
				(pads allowed)
				(copperpour not_allowed)
				(footprints allowed)
			)
			(placement
				(enabled no)
				(sheetname "")
			)
			(fill
				(thermal_gap 0.5)
				(thermal_bridge_width 0.5)
				(island_removal_mode 0)
			)
			(polygon
				(pts
					(xy 387.64972 -111.2647) (xy 387.64972 -111.6457) (xy 387.82498 -111.6457) (xy 387.825234 -111.2647)
				)
			)
		)
		(zone
			(layer "B.Cu")
			(hatch none 0.5)
			(connect_pads
				(clearance 0)
			)
			(min_thickness 0.25)
			(keepout
				(tracks not_allowed)
				(vias allowed)
				(pads allowed)
				(copperpour not_allowed)
				(footprints allowed)
			)
			(placement
				(enabled no)
				(sheetname "")
			)
			(fill
				(thermal_gap 0.5)
				(thermal_bridge_width 0.5)
				(island_removal_mode 0)
			)
			(polygon
				(pts
					(xy 387.64972 -111.2647) (xy 387.64972 -111.6457) (xy 387.82498 -111.6457) (xy 387.825234 -111.2647)
				)
			)
		)
	)
)
